(kicad_pcb
	(version 20260206)
	(generator "pcbnew")
	(generator_version "10.0")
	(general
		(thickness 1.6)
		(legacy_teardrops no)
	)
	(paper "A4")
	(title_block
		(title "01162023_DA0F0TEBIF0_F0T_Expander_BD_F_brd_V02_OCP.brd")
		(comment 1 "Grand Teton / footprints 4035-4042 of 9728")
	)
	(layers
		(0 "F.Cu" signal "TOP")
		(4 "In1.Cu" signal "GND")
		(6 "In2.Cu" signal "VCC")
		(8 "In3.Cu" signal "VCC1")
		(10 "In4.Cu" signal "GND1")
		(12 "In5.Cu" signal "IN1")
		(14 "In6.Cu" signal "GND2")
		(16 "In7.Cu" signal "IN2")
		(18 "In8.Cu" signal "GND3")
		(20 "In9.Cu" signal "IN3")
		(22 "In10.Cu" signal "GND4")
		(24 "In11.Cu" signal "IN4")
		(26 "In12.Cu" signal "GND5")
		(28 "In13.Cu" signal "IN5")
		(30 "In14.Cu" signal "GND6")
		(32 "In15.Cu" signal "IN6")
		(34 "In16.Cu" signal "GND7")
		(2 "B.Cu" signal "BOTTOM")
		(9 "F.Adhes" user "F.Adhesive")
		(11 "B.Adhes" user "B.Adhesive")
		(13 "F.Paste" user "Package Geometry/Pastemask Top")
		(15 "B.Paste" user "Package Geometry/Pastemask Bottom")
		(5 "F.SilkS" user "Ref Des/Silkscreen Top")
		(7 "B.SilkS" user "Ref Des/Silkscreen Bottom")
		(1 "F.Mask" user "Board Geometry/Soldermask Top")
		(3 "B.Mask" user "Board Geometry/Soldermask Bottom")
		(17 "Dwgs.User" user "User.Drawings")
		(19 "Cmts.User" user "User.Comments")
		(21 "Eco1.User" user "User.Eco1")
		(23 "Eco2.User" user "User.Eco2")
		(25 "Edge.Cuts" user "Board Geometry/Outline")
		(27 "Margin" user)
		(31 "F.CrtYd" user "Package Geometry/Place Bound Top")
		(29 "B.CrtYd" user "Package Geometry/Place Bound Bottom")
		(35 "F.Fab" user "Ref Des/Assembly Top")
		(33 "B.Fab" user "Ref Des/Assembly Bottom")
	)
	(footprint ""
		(layer "F.Cu")
		(at 210.439 -193.675 180)
		(property "Reference" "R1532"
			(at 0 0 180)
			(layer "F.SilkS")
			(hide yes)
			(effects
				(font
					(size 1.27 1.27)
				)
			)
		)
		(property "Value" ""
			(at 0 0 180)
			(layer "F.Fab")
			(effects
				(font
					(size 1.27 1.27)
				)
			)
		)
		(duplicate_pad_numbers_are_jumpers no)
		(fp_line
			(start 0.7874 0.4064)
			(end -0.7874 0.4064)
			(stroke
				(width 0.1524)
				(type default)
			)
			(layer "F.SilkS")
		)
		(fp_line
			(start 0.7874 -0.4064)
			(end 0.7874 0.4064)
			(stroke
				(width 0.1524)
				(type default)
			)
			(layer "F.SilkS")
		)
		(fp_line
			(start -0.7874 0.4064)
			(end -0.7874 -0.4064)
			(stroke
				(width 0.1524)
				(type default)
			)
			(layer "F.SilkS")
		)
		(fp_line
			(start -0.7874 -0.4064)
			(end 0.7874 -0.4064)
			(stroke
				(width 0.1524)
				(type default)
			)
			(layer "F.SilkS")
		)
		(fp_line
			(start 0.67945 0.3048)
			(end 0.120396 0.3048)
			(stroke
				(width 0.1)
				(type default)
			)
			(layer "F.Fab")
		)
		(fp_line
			(start 0.67945 -0.3048)
			(end 0.67945 0.3048)
			(stroke
				(width 0.1)
				(type default)
			)
			(layer "F.Fab")
		)
		(fp_line
			(start 0.12065 -0.2794)
			(end 0.12065 -0.3048)
			(stroke
				(width 0.1)
				(type default)
			)
			(layer "F.Fab")
		)
		(fp_line
			(start 0.12065 -0.3048)
			(end 0.67945 -0.3048)
			(stroke
				(width 0.1)
				(type default)
			)
			(layer "F.Fab")
		)
		(fp_line
			(start 0.120396 0.3048)
			(end 0.120396 0.2794)
			(stroke
				(width 0.1)
				(type default)
			)
			(layer "F.Fab")
		)
		(fp_line
			(start 0.120396 0.2794)
			(end -0.12065 0.2794)
			(stroke
				(width 0.1)
				(type default)
			)
			(layer "F.Fab")
		)
		(fp_line
			(start -0.12065 0.3048)
			(end -0.67945 0.3048)
			(stroke
				(width 0.1)
				(type default)
			)
			(layer "F.Fab")
		)
		(fp_line
			(start -0.12065 0.2794)
			(end -0.12065 0.3048)
			(stroke
				(width 0.1)
				(type default)
			)
			(layer "F.Fab")
		)
		(fp_line
			(start -0.12065 -0.2794)
			(end 0.12065 -0.2794)
			(stroke
				(width 0.1)
				(type default)
			)
			(layer "F.Fab")
		)
		(fp_line
			(start -0.12065 -0.305054)
			(end -0.12065 -0.2794)
			(stroke
				(width 0.1)
				(type default)
			)
			(layer "F.Fab")
		)
		(fp_line
			(start -0.67945 0.3048)
			(end -0.67945 -0.305054)
			(stroke
				(width 0.1)
				(type default)
			)
			(layer "F.Fab")
		)
		(fp_line
			(start -0.67945 -0.305054)
			(end -0.12065 -0.305054)
			(stroke
				(width 0.1)
				(type default)
			)
			(layer "F.Fab")
		)
		(pad "1" smd circle
			(at -0.40005 0 180)
			(size 0 0)
			(layers "F.Cu" "F.Mask" "F.Paste")
			(net "SMB_NIC7_R_SDA")
		)
		(pad "2" smd circle
			(at 0.40005 0 180)
			(size 0 0)
			(layers "F.Cu" "F.Mask" "F.Paste")
			(net "P1V2_AUX")
		)
	)
	(footprint ""
		(layer "F.Cu")
		(at 401.426172 -39.73576 -90)
		(property "Reference" "R5578"
			(at 0 0 270)
			(layer "F.SilkS")
			(hide yes)
			(effects
				(font
					(size 1.27 1.27)
				)
			)
		)
		(property "Value" ""
			(at 0 0 270)
			(layer "F.Fab")
			(effects
				(font
					(size 1.27 1.27)
				)
			)
		)
		(duplicate_pad_numbers_are_jumpers no)
		(fp_line
			(start -0.7874 0.4064)
			(end -0.7874 -0.4064)
			(stroke
				(width 0.1524)
				(type default)
			)
			(layer "F.SilkS")
		)
		(fp_line
			(start 0.7874 0.4064)
			(end -0.7874 0.4064)
			(stroke
				(width 0.1524)
				(type default)
			)
			(layer "F.SilkS")
		)
		(fp_line
			(start -0.7874 -0.4064)
			(end 0.7874 -0.4064)
			(stroke
				(width 0.1524)
				(type default)
			)
			(layer "F.SilkS")
		)
		(fp_line
			(start 0.7874 -0.4064)
			(end 0.7874 0.4064)
			(stroke
				(width 0.1524)
				(type default)
			)
			(layer "F.SilkS")
		)
		(fp_line
			(start -0.67945 0.3048)
			(end -0.67945 -0.305054)
			(stroke
				(width 0.1)
				(type default)
			)
			(layer "F.Fab")
		)
		(fp_line
			(start -0.12065 0.3048)
			(end -0.67945 0.3048)
			(stroke
				(width 0.1)
				(type default)
			)
			(layer "F.Fab")
		)
		(fp_line
			(start 0.120396 0.3048)
			(end 0.120396 0.2794)
			(stroke
				(width 0.1)
				(type default)
			)
			(layer "F.Fab")
		)
		(fp_line
			(start 0.67945 0.3048)
			(end 0.120396 0.3048)
			(stroke
				(width 0.1)
				(type default)
			)
			(layer "F.Fab")
		)
		(fp_line
			(start -0.12065 0.2794)
			(end -0.12065 0.3048)
			(stroke
				(width 0.1)
				(type default)
			)
			(layer "F.Fab")
		)
		(fp_line
			(start 0.120396 0.2794)
			(end -0.12065 0.2794)
			(stroke
				(width 0.1)
				(type default)
			)
			(layer "F.Fab")
		)
		(fp_line
			(start -0.12065 -0.2794)
			(end 0.12065 -0.2794)
			(stroke
				(width 0.1)
				(type default)
			)
			(layer "F.Fab")
		)
		(fp_line
			(start 0.12065 -0.2794)
			(end 0.12065 -0.3048)
			(stroke
				(width 0.1)
				(type default)
			)
			(layer "F.Fab")
		)
		(fp_line
			(start 0.12065 -0.3048)
			(end 0.67945 -0.3048)
			(stroke
				(width 0.1)
				(type default)
			)
			(layer "F.Fab")
		)
		(fp_line
			(start 0.67945 -0.3048)
			(end 0.67945 0.3048)
			(stroke
				(width 0.1)
				(type default)
			)
			(layer "F.Fab")
		)
		(fp_line
			(start -0.67945 -0.305054)
			(end -0.12065 -0.305054)
			(stroke
				(width 0.1)
				(type default)
			)
			(layer "F.Fab")
		)
		(fp_line
			(start -0.12065 -0.305054)
			(end -0.12065 -0.2794)
			(stroke
				(width 0.1)
				(type default)
			)
			(layer "F.Fab")
		)
		(pad "1" smd circle
			(at -0.40005 0 270)
			(size 0 0)
			(layers "F.Cu" "F.Mask" "F.Paste")
			(net "P3V3_AUX")
		)
		(pad "2" smd circle
			(at 0.40005 0 270)
			(size 0 0)
			(layers "F.Cu" "F.Mask" "F.Paste")
			(net "SSD14_AUX_P3V3_EN")
		)
	)
	(footprint ""
		(layer "F.Cu")
		(at 428.319438 -142.590266 180)
		(property "Reference" "C649"
			(at 0 0 180)
			(layer "F.SilkS")
			(hide yes)
			(effects
				(font
					(size 1.27 1.27)
				)
			)
		)
		(property "Value" ""
			(at 0 0 180)
			(layer "F.Fab")
			(effects
				(font
					(size 1.27 1.27)
				)
			)
		)
		(duplicate_pad_numbers_are_jumpers no)
		(fp_line
			(start 0.299974 0.150114)
			(end -0.299974 0.150114)
			(stroke
				(width 0.1)
				(type default)
			)
			(layer "F.Fab")
		)
		(fp_line
			(start 0.299974 -0.150114)
			(end 0.299974 0.150114)
			(stroke
				(width 0.1)
				(type default)
			)
			(layer "F.Fab")
		)
		(fp_line
			(start -0.299974 0.150114)
			(end -0.299974 -0.150114)
			(stroke
				(width 0.1)
				(type default)
			)
			(layer "F.Fab")
		)
		(fp_line
			(start -0.299974 -0.150114)
			(end 0.299974 -0.150114)
			(stroke
				(width 0.1)
				(type default)
			)
			(layer "F.Fab")
		)
		(pad "1" smd rect
			(at -0.2667 0 180)
			(size 0.3048 0.381)
			(layers "F.Cu" "F.Mask" "F.Paste")
			(net "P5E_PEX3_STN0_TX_DN<8>")
		)
		(pad "2" smd rect
			(at 0.2667 0 180)
			(size 0.3048 0.381)
			(layers "F.Cu" "F.Mask" "F.Paste")
			(net "P5E_PEX3_STN0_TX_C_DN<8>")
		)
	)
	(footprint ""
		(layer "F.Cu")
		(at 30.081982 -292.991032 180)
		(property "Reference" "C3032"
			(at 0 0 180)
			(layer "F.SilkS")
			(hide yes)
			(effects
				(font
					(size 1.27 1.27)
				)
			)
		)
		(property "Value" ""
			(at 0 0 180)
			(layer "F.Fab")
			(effects
				(font
					(size 1.27 1.27)
				)
			)
		)
		(duplicate_pad_numbers_are_jumpers no)
		(fp_line
			(start 1.2954 0.5842)
			(end -1.2954 0.5842)
			(stroke
				(width 0.1524)
				(type default)
			)
			(layer "F.SilkS")
		)
		(fp_line
			(start 1.2954 -0.5842)
			(end 1.2954 0.5842)
			(stroke
				(width 0.1524)
				(type default)
			)
			(layer "F.SilkS")
		)
		(fp_line
			(start -1.2954 0.5842)
			(end -1.2954 -0.5842)
			(stroke
				(width 0.1524)
				(type default)
			)
			(layer "F.SilkS")
		)
		(fp_line
			(start -1.2954 -0.5842)
			(end 1.2954 -0.5842)
			(stroke
				(width 0.1524)
				(type default)
			)
			(layer "F.SilkS")
		)
		(fp_line
			(start 1.1938 0.4064)
			(end 0.8636 0.4064)
			(stroke
				(width 0.1)
				(type default)
			)
			(layer "F.Fab")
		)
		(fp_line
			(start 1.1938 -0.4064)
			(end 1.1938 0.4064)
			(stroke
				(width 0.1)
				(type default)
			)
			(layer "F.Fab")
		)
		(fp_line
			(start 0.8636 0.4572)
			(end -0.8636 0.4572)
			(stroke
				(width 0.1)
				(type default)
			)
			(layer "F.Fab")
		)
		(fp_line
			(start 0.8636 0.4064)
			(end 0.8636 0.4572)
			(stroke
				(width 0.1)
				(type default)
			)
			(layer "F.Fab")
		)
		(fp_line
			(start 0.8636 -0.4064)
			(end 1.1938 -0.4064)
			(stroke
				(width 0.1)
				(type default)
			)
			(layer "F.Fab")
		)
		(fp_line
			(start 0.8636 -0.4572)
			(end 0.8636 -0.4064)
			(stroke
				(width 0.1)
				(type default)
			)
			(layer "F.Fab")
		)
		(fp_line
			(start -0.8636 0.4572)
			(end -0.8636 0.4064)
			(stroke
				(width 0.1)
				(type default)
			)
			(layer "F.Fab")
		)
		(fp_line
			(start -0.8636 0.4064)
			(end -1.1938 0.4064)
			(stroke
				(width 0.1)
				(type default)
			)
			(layer "F.Fab")
		)
		(fp_line
			(start -0.8636 -0.4064)
			(end -0.8636 -0.4572)
			(stroke
				(width 0.1)
				(type default)
			)
			(layer "F.Fab")
		)
		(fp_line
			(start -0.8636 -0.4572)
			(end 0.8636 -0.4572)
			(stroke
				(width 0.1)
				(type default)
			)
			(layer "F.Fab")
		)
		(fp_line
			(start -1.1938 0.4064)
			(end -1.1938 -0.4064)
			(stroke
				(width 0.1)
				(type default)
			)
			(layer "F.Fab")
		)
		(fp_line
			(start -1.1938 -0.4064)
			(end -0.8636 -0.4064)
			(stroke
				(width 0.1)
				(type default)
			)
			(layer "F.Fab")
		)
		(pad "1" smd rect
			(at -0.7366 0 90)
			(size 0.7112 0.8128)
			(layers "F.Cu" "F.Mask" "F.Paste")
			(net "PCEPLL2_VDDA18_PEX0_R")
		)
		(pad "2" smd rect
			(at 0.7366 0 90)
			(size 0.7112 0.8128)
			(layers "F.Cu" "F.Mask" "F.Paste")
			(net "GND")
		)
	)
	(footprint ""
		(layer "F.Cu")
		(at 262.353298 -294.591232)
		(property "Reference" "L122"
			(at 0 0 0)
			(layer "F.SilkS")
			(hide yes)
			(effects
				(font
					(size 1.27 1.27)
				)
			)
		)
		(property "Value" ""
			(at 0 0 0)
			(layer "F.Fab")
			(effects
				(font
					(size 1.27 1.27)
				)
			)
		)
		(duplicate_pad_numbers_are_jumpers no)
		(fp_line
			(start -1.63576 -0.8128)
			(end -1.63576 0.8128)
			(stroke
				(width 0.1524)
				(type default)
			)
			(layer "F.SilkS")
		)
		(fp_line
			(start -1.63576 -0.8128)
			(end 1.63576 -0.8128)
			(stroke
				(width 0.1524)
				(type default)
			)
			(layer "F.SilkS")
		)
		(fp_line
			(start 1.63576 -0.8128)
			(end 1.63576 0.8128)
			(stroke
				(width 0.1524)
				(type default)
			)
			(layer "F.SilkS")
		)
		(fp_line
			(start 1.63576 0.8128)
			(end -1.63576 0.8128)
			(stroke
				(width 0.1524)
				(type default)
			)
			(layer "F.SilkS")
		)
		(fp_line
			(start -1.56083 -0.738632)
			(end -1.56083 0.7366)
			(stroke
				(width 0.1)
				(type default)
			)
			(layer "F.Fab")
		)
		(fp_line
			(start -1.56083 0.7366)
			(end -1.524 0.7366)
			(stroke
				(width 0.1)
				(type default)
			)
			(layer "F.Fab")
		)
		(fp_line
			(start -1.524 0.7366)
			(end 1.524 0.7366)
			(stroke
				(width 0.1)
				(type default)
			)
			(layer "F.Fab")
		)
		(fp_line
			(start 1.524 0.7366)
			(end 1.560576 0.7366)
			(stroke
				(width 0.1)
				(type default)
			)
			(layer "F.Fab")
		)
		(fp_line
			(start 1.560576 -0.738632)
			(end -1.56083 -0.738632)
			(stroke
				(width 0.1)
				(type default)
			)
			(layer "F.Fab")
		)
		(fp_line
			(start 1.560576 0.7366)
			(end 1.560576 -0.738632)
			(stroke
				(width 0.1)
				(type default)
			)
			(layer "F.Fab")
		)
		(pad "1" smd rect
			(at -0.94996 0 180)
			(size 1.1176 1.3716)
			(layers "F.Cu" "F.Mask" "F.Paste")
			(net "P1V8_PLL0_PEX2")
		)
		(pad "2" smd rect
			(at 0.94996 0 180)
			(size 1.1176 1.3716)
			(layers "F.Cu" "F.Mask" "F.Paste")
			(net "PCEPLL2_VDDA18_PEX2")
		)
	)
	(footprint ""
		(layer "F.Cu")
		(at 328.022204 -350.098614 90)
		(property "Reference" "C565"
			(at 0 0 90)
			(layer "F.SilkS")
			(hide yes)
			(effects
				(font
					(size 1.27 1.27)
				)
			)
		)
		(property "Value" ""
			(at 0 0 90)
			(layer "F.Fab")
			(effects
				(font
					(size 1.27 1.27)
				)
			)
		)
		(duplicate_pad_numbers_are_jumpers no)
		(fp_line
			(start 0.299974 -0.150114)
			(end 0.299974 0.150114)
			(stroke
				(width 0.1)
				(type default)
			)
			(layer "F.Fab")
		)
		(fp_line
			(start -0.299974 -0.150114)
			(end 0.299974 -0.150114)
			(stroke
				(width 0.1)
				(type default)
			)
			(layer "F.Fab")
		)
		(fp_line
			(start 0.299974 0.150114)
			(end -0.299974 0.150114)
			(stroke
				(width 0.1)
				(type default)
			)
			(layer "F.Fab")
		)
		(fp_line
			(start -0.299974 0.150114)
			(end -0.299974 -0.150114)
			(stroke
				(width 0.1)
				(type default)
			)
			(layer "F.Fab")
		)
		(pad "1" smd rect
			(at -0.2667 0 90)
			(size 0.3048 0.381)
			(layers "F.Cu" "F.Mask" "F.Paste")
			(net "P5E_PEX2_STN6_TX_DP<104>")
		)
		(pad "2" smd rect
			(at 0.2667 0 90)
			(size 0.3048 0.381)
			(layers "F.Cu" "F.Mask" "F.Paste")
			(net "P5E_PEX2_STN6_TX_C_DP<104>")
		)
	)
	(footprint ""
		(layer "F.Cu")
		(at 14.656308 -304.10023 -90)
		(property "Reference" "PC221"
			(at 0 0 270)
			(layer "F.SilkS")
			(hide yes)
			(effects
				(font
					(size 1.27 1.27)
				)
			)
		)
		(property "Value" ""
			(at 0 0 270)
			(layer "F.Fab")
			(effects
				(font
					(size 1.27 1.27)
				)
			)
		)
		(duplicate_pad_numbers_are_jumpers no)
		(fp_line
			(start -0.7874 0.4064)
			(end -0.7874 -0.4064)
			(stroke
				(width 0.1524)
				(type default)
			)
			(layer "F.SilkS")
		)
		(fp_line
			(start 0.7874 0.4064)
			(end -0.7874 0.4064)
			(stroke
				(width 0.1524)
				(type default)
			)
			(layer "F.SilkS")
		)
		(fp_line
			(start -0.7874 -0.4064)
			(end 0.7874 -0.4064)
			(stroke
				(width 0.1524)
				(type default)
			)
			(layer "F.SilkS")
		)
		(fp_line
			(start 0.7874 -0.4064)
			(end 0.7874 0.4064)
			(stroke
				(width 0.1524)
				(type default)
			)
			(layer "F.SilkS")
		)
		(fp_line
			(start -0.67945 0.3048)
			(end -0.67945 -0.305054)
			(stroke
				(width 0.1)
				(type default)
			)
			(layer "F.Fab")
		)
		(fp_line
			(start -0.12065 0.3048)
			(end -0.67945 0.3048)
			(stroke
				(width 0.1)
				(type default)
			)
			(layer "F.Fab")
		)
		(fp_line
			(start 0.120396 0.3048)
			(end 0.120396 0.2794)
			(stroke
				(width 0.1)
				(type default)
			)
			(layer "F.Fab")
		)
		(fp_line
			(start 0.67945 0.3048)
			(end 0.120396 0.3048)
			(stroke
				(width 0.1)
				(type default)
			)
			(layer "F.Fab")
		)
		(fp_line
			(start -0.12065 0.2794)
			(end -0.12065 0.3048)
			(stroke
				(width 0.1)
				(type default)
			)
			(layer "F.Fab")
		)
		(fp_line
			(start 0.120396 0.2794)
			(end -0.12065 0.2794)
			(stroke
				(width 0.1)
				(type default)
			)
			(layer "F.Fab")
		)
		(fp_line
			(start -0.12065 -0.2794)
			(end 0.12065 -0.2794)
			(stroke
				(width 0.1)
				(type default)
			)
			(layer "F.Fab")
		)
		(fp_line
			(start 0.12065 -0.2794)
			(end 0.12065 -0.3048)
			(stroke
				(width 0.1)
				(type default)
			)
			(layer "F.Fab")
		)
		(fp_line
			(start 0.12065 -0.3048)
			(end 0.67945 -0.3048)
			(stroke
				(width 0.1)
				(type default)
			)
			(layer "F.Fab")
		)
		(fp_line
			(start 0.67945 -0.3048)
			(end 0.67945 0.3048)
			(stroke
				(width 0.1)
				(type default)
			)
			(layer "F.Fab")
		)
		(fp_line
			(start -0.67945 -0.305054)
			(end -0.12065 -0.305054)
			(stroke
				(width 0.1)
				(type default)
			)
			(layer "F.Fab")
		)
		(fp_line
			(start -0.12065 -0.305054)
			(end -0.12065 -0.2794)
			(stroke
				(width 0.1)
				(type default)
			)
			(layer "F.Fab")
		)
		(pad "1" smd circle
			(at -0.40005 0 270)
			(size 0 0)
			(layers "F.Cu" "F.Mask" "F.Paste")
			(net "P1V25_PEX0_REF")
		)
		(pad "2" smd circle
			(at 0.40005 0 270)
			(size 0 0)
			(layers "F.Cu" "F.Mask" "F.Paste")
			(net "GND")
		)
	)
	(footprint ""
		(layer "F.Cu")
		(at 3.155188 -53.468524 90)
		(property "Reference" "PC535"
			(at 0 0 90)
			(layer "F.SilkS")
			(hide yes)
			(effects
				(font
					(size 1.27 1.27)
				)
			)
		)
		(property "Value" ""
			(at 0 0 90)
			(layer "F.Fab")
			(effects
				(font
					(size 1.27 1.27)
				)
			)
		)
		(duplicate_pad_numbers_are_jumpers no)
		(fp_line
			(start 1.524 -0.762)
			(end 1.524 0.762)
			(stroke
				(width 0.1524)
				(type default)
			)
			(layer "F.SilkS")
		)
		(fp_line
			(start -1.524 -0.762)
			(end 1.524 -0.762)
			(stroke
				(width 0.1524)
				(type default)
			)
			(layer "F.SilkS")
		)
		(fp_line
			(start 1.524 0.762)
			(end -1.524 0.762)
			(stroke
				(width 0.1524)
				(type default)
			)
			(layer "F.SilkS")
		)
		(fp_line
			(start -1.524 0.762)
			(end -1.524 -0.762)
			(stroke
				(width 0.1524)
				(type default)
			)
			(layer "F.SilkS")
		)
		(fp_line
			(start 1.1049 -0.724916)
			(end -1.1049 -0.724916)
			(stroke
				(width 0.1)
				(type default)
			)
			(layer "F.Fab")
		)
		(fp_line
			(start -1.1049 -0.724916)
			(end -1.1049 0.724916)
			(stroke
				(width 0.1)
				(type default)
			)
			(layer "F.Fab")
		)
		(fp_line
			(start 1.1049 0.724916)
			(end 1.1049 -0.724916)
			(stroke
				(width 0.1)
				(type default)
			)
			(layer "F.Fab")
		)
		(fp_line
			(start -1.1049 0.724916)
			(end 1.1049 0.724916)
			(stroke
				(width 0.1)
				(type default)
			)
			(layer "F.Fab")
		)
		(pad "1" smd rect
			(at -0.889 0 270)
			(size 1.016 1.27)
			(layers "F.Cu" "F.Mask" "F.Paste")
			(net "GND")
		)
		(pad "2" smd rect
			(at 0.889 0 270)
			(size 1.016 1.27)
			(layers "F.Cu" "F.Mask" "F.Paste")
			(net "P3V3_AUX")
		)
	)
)
